# S9S_MB_2U (Grand Teton) — schematic netlist excerpt (pin names and nets, part order shuffled) for the footprints in the layout excerpt that follows; sources: Cadence DE-HDL packaged netlist, KiCad conversion of 03242023_DA0F0TMBIJ0_F0T_Motherboard_J_brd_V01_OCP.brd

R1933  Q_RES  33.2 1% CHIP  pkg 0402LF  page 14 : A = SMB_S3M_CPU0_PIROM_3V3AUX_SDA ; B = SMB_S3M_CPU0_PIROM_3V3AUX_SDA_1
C1832  Q_CAP  0.1UF 25V 10% X7R  pkg 0402  page 159 : A = P12V_OCP_V3_2 ; B = GND

(kicad_pcb
	(version 20260206)
	(generator "pcbnew")
	(generator_version "10.0")
	(general
		(thickness 1.6)
		(legacy_teardrops no)
	)
	(paper "A4")
	(title_block
		(title "03242023_DA0F0TMBIJ0_F0T_Motherboard_J_brd_V01_OCP.brd")
		(comment 1 "Grand Teton / footprints 5815-5816 of 6105")
	)
	(layers
		(0 "F.Cu" signal "TOP")
		(4 "In1.Cu" signal "GND")
		(6 "In2.Cu" signal "IN1")
		(8 "In3.Cu" signal "GND1")
		(10 "In4.Cu" signal "IN2")
		(12 "In5.Cu" signal "GND2")
		(14 "In6.Cu" signal "IN3")
		(16 "In7.Cu" signal "GND3")
		(18 "In8.Cu" signal "VCC")
		(20 "In9.Cu" signal "VCC1")
		(22 "In10.Cu" signal "GND4")
		(24 "In11.Cu" signal "IN4")
		(26 "In12.Cu" signal "GND5")
		(28 "In13.Cu" signal "IN5")
		(30 "In14.Cu" signal "GND6")
		(32 "In15.Cu" signal "IN6")
		(34 "In16.Cu" signal "GND7")
		(2 "B.Cu" signal "BOTTOM")
		(9 "F.Adhes" user "F.Adhesive")
		(11 "B.Adhes" user "B.Adhesive")
		(13 "F.Paste" user "Package Geometry/Pastemask Top")
		(15 "B.Paste" user "Package Geometry/Pastemask Bottom")
		(5 "F.SilkS" user "Ref Des/Silkscreen Top")
		(7 "B.SilkS" user "Ref Des/Silkscreen Bottom")
		(1 "F.Mask" user "Board Geometry/Soldermask Top")
		(3 "B.Mask" user "Board Geometry/Soldermask Bottom")
		(17 "Dwgs.User" user "User.Drawings")
		(19 "Cmts.User" user "User.Comments")
		(21 "Eco1.User" user "User.Eco1")
		(23 "Eco2.User" user "User.Eco2")
		(25 "Edge.Cuts" user "Board Geometry/Outline")
		(27 "Margin" user)
		(31 "F.CrtYd" user "Package Geometry/Place Bound Top")
		(29 "B.CrtYd" user "Package Geometry/Place Bound Bottom")
		(35 "F.Fab" user "Ref Des/Assembly Top")
		(33 "B.Fab" user "Ref Des/Assembly Bottom")
	)
	(footprint ""
		(layer "B.Cu")
		(at 66.162174 -16.37157)
		(property "Reference" "C1832"
			(at 0 0 0)
			(layer "B.SilkS")
			(hide yes)
			(effects
				(font
					(size 1.27 1.27)
				)
				(justify mirror)
			)
		)
		(property "Value" ""
			(at 0 0 0)
			(layer "B.Fab")
			(effects
				(font
					(size 1.27 1.27)
				)
				(justify mirror)
			)
		)
		(duplicate_pad_numbers_are_jumpers no)
		(fp_line
			(start -0.7874 -0.4064)
			(end -0.7874 0.4064)
			(stroke
				(width 0.1524)
				(type default)
			)
			(layer "B.SilkS")
		)
		(fp_line
			(start -0.7874 0.4064)
			(end 0.7874 0.4064)
			(stroke
				(width 0.1524)
				(type default)
			)
			(layer "B.SilkS")
		)
		(fp_line
			(start 0.7874 -0.4064)
			(end -0.7874 -0.4064)
			(stroke
				(width 0.1524)
				(type default)
			)
			(layer "B.SilkS")
		)
		(fp_line
			(start 0.7874 0.4064)
			(end 0.7874 -0.4064)
			(stroke
				(width 0.1524)
				(type default)
			)
			(layer "B.SilkS")
		)
		(fp_line
			(start -0.67945 -0.3048)
			(end -0.67945 0.3048)
			(stroke
				(width 0.1)
				(type default)
			)
			(layer "B.Fab")
		)
		(fp_line
			(start -0.67945 0.3048)
			(end -0.120396 0.3048)
			(stroke
				(width 0.1)
				(type default)
			)
			(layer "B.Fab")
		)
		(fp_line
			(start -0.12065 -0.3048)
			(end -0.67945 -0.3048)
			(stroke
				(width 0.1)
				(type default)
			)
			(layer "B.Fab")
		)
		(fp_line
			(start -0.12065 -0.2794)
			(end -0.12065 -0.3048)
			(stroke
				(width 0.1)
				(type default)
			)
			(layer "B.Fab")
		)
		(fp_line
			(start -0.120396 0.2794)
			(end 0.12065 0.2794)
			(stroke
				(width 0.1)
				(type default)
			)
			(layer "B.Fab")
		)
		(fp_line
			(start -0.120396 0.3048)
			(end -0.120396 0.2794)
			(stroke
				(width 0.1)
				(type default)
			)
			(layer "B.Fab")
		)
		(fp_line
			(start 0.12065 -0.305054)
			(end 0.12065 -0.2794)
			(stroke
				(width 0.1)
				(type default)
			)
			(layer "B.Fab")
		)
		(fp_line
			(start 0.12065 -0.2794)
			(end -0.12065 -0.2794)
			(stroke
				(width 0.1)
				(type default)
			)
			(layer "B.Fab")
		)
		(fp_line
			(start 0.12065 0.2794)
			(end 0.12065 0.3048)
			(stroke
				(width 0.1)
				(type default)
			)
			(layer "B.Fab")
		)
		(fp_line
			(start 0.12065 0.3048)
			(end 0.67945 0.3048)
			(stroke
				(width 0.1)
				(type default)
			)
			(layer "B.Fab")
		)
		(fp_line
			(start 0.67945 -0.305054)
			(end 0.12065 -0.305054)
			(stroke
				(width 0.1)
				(type default)
			)
			(layer "B.Fab")
		)
		(fp_line
			(start 0.67945 0.3048)
			(end 0.67945 -0.305054)
			(stroke
				(width 0.1)
				(type default)
			)
			(layer "B.Fab")
		)
		(pad "1" smd circle
			(at 0.40005 0 180)
			(size 0 0)
			(layers "B.Cu" "B.Mask" "B.Paste")
			(net "P12V_OCP_V3_2")
		)
		(pad "2" smd circle
			(at -0.40005 0 180)
			(size 0 0)
			(layers "B.Cu" "B.Mask" "B.Paste")
			(net "GND")
		)
	)
	(footprint ""
		(layer "B.Cu")
		(at 180.90388 -330.495148 180)
		(property "Reference" "R1933"
			(at 0 0 0)
			(layer "B.SilkS")
			(hide yes)
			(effects
				(font
					(size 1.27 1.27)
				)
				(justify mirror)
			)
		)
		(property "Value" ""
			(at 0 0 0)
			(layer "B.Fab")
			(effects
				(font
					(size 1.27 1.27)
				)
				(justify mirror)
			)
		)
		(duplicate_pad_numbers_are_jumpers no)
		(fp_line
			(start 0.7874 0.4064)
			(end 0.7874 -0.4064)
			(stroke
				(width 0.1524)
				(type default)
			)
			(layer "B.SilkS")
		)
		(fp_line
			(start 0.7874 -0.4064)
			(end -0.7874 -0.4064)
			(stroke
				(width 0.1524)
				(type default)
			)
			(layer "B.SilkS")
		)
		(fp_line
			(start -0.7874 0.4064)
			(end 0.7874 0.4064)
			(stroke
				(width 0.1524)
				(type default)
			)
			(layer "B.SilkS")
		)
		(fp_line
			(start -0.7874 -0.4064)
			(end -0.7874 0.4064)
			(stroke
				(width 0.1524)
				(type default)
			)
			(layer "B.SilkS")
		)
		(fp_line
			(start 0.67945 0.3048)
			(end 0.67945 -0.305054)
			(stroke
				(width 0.1)
				(type default)
			)
			(layer "B.Fab")
		)
		(fp_line
			(start 0.67945 -0.305054)
			(end 0.12065 -0.305054)
			(stroke
				(width 0.1)
				(type default)
			)
			(layer "B.Fab")
		)
		(fp_line
			(start 0.12065 0.3048)
			(end 0.67945 0.3048)
			(stroke
				(width 0.1)
				(type default)
			)
			(layer "B.Fab")
		)
		(fp_line
			(start 0.12065 0.2794)
			(end 0.12065 0.3048)
			(stroke
				(width 0.1)
				(type default)
			)
			(layer "B.Fab")
		)
		(fp_line
			(start 0.12065 -0.2794)
			(end -0.12065 -0.2794)
			(stroke
				(width 0.1)
				(type default)
			)
			(layer "B.Fab")
		)
		(fp_line
			(start 0.12065 -0.305054)
			(end 0.12065 -0.2794)
			(stroke
				(width 0.1)
				(type default)
			)
			(layer "B.Fab")
		)
		(fp_line
			(start -0.120396 0.3048)
			(end -0.120396 0.2794)
			(stroke
				(width 0.1)
				(type default)
			)
			(layer "B.Fab")
		)
		(fp_line
			(start -0.120396 0.2794)
			(end 0.12065 0.2794)
			(stroke
				(width 0.1)
				(type default)
			)
			(layer "B.Fab")
		)
		(fp_line
			(start -0.12065 -0.2794)
			(end -0.12065 -0.3048)
			(stroke
				(width 0.1)
				(type default)
			)
			(layer "B.Fab")
		)
		(fp_line
			(start -0.12065 -0.3048)
			(end -0.67945 -0.3048)
			(stroke
				(width 0.1)
				(type default)
			)
			(layer "B.Fab")
		)
		(fp_line
			(start -0.67945 0.3048)
			(end -0.120396 0.3048)
			(stroke
				(width 0.1)
				(type default)
			)
			(layer "B.Fab")
		)
		(fp_line
			(start -0.67945 -0.3048)
			(end -0.67945 0.3048)
			(stroke
				(width 0.1)
				(type default)
			)
			(layer "B.Fab")
		)
		(pad "1" smd circle
			(at 0.40005 0)
			(size 0 0)
			(layers "B.Cu" "B.Mask" "B.Paste")
			(net "SMB_S3M_CPU0_PIROM_3V3AUX_SDA")
		)
		(pad "2" smd circle
			(at -0.40005 0)
			(size 0 0)
			(layers "B.Cu" "B.Mask" "B.Paste")
			(net "SMB_S3M_CPU0_PIROM_3V3AUX_SDA_1")
		)
	)
)
